# S9S_MB_2U (Grand Teton) — schematic netlist excerpt (pin names and nets, part order shuffled) for the footprints in the layout excerpt that follows; sources: Cadence DE-HDL packaged netlist, KiCad conversion of 03242023_DA0F0TMBIJ0_F0T_Motherboard_J_brd_V01_OCP.brd

Q103  MOSFET_NCH_DUAL  PJT138K IC  pkg SOT363XD  page 147
  S1  = GND
  G1  = GPU_HMC_PRSNT_N
  D2  = GPU_HMC_PRSNT_ISO_N
  S2  = GND
  G2  = GPU_HMC_PRSNT
  D1  = GPU_HMC_PRSNT

C1545  Q_CAP_DIFFBUS  DIFF BUS_0.22UF 6.3V 20% X6S  pkg C0201  page 177 : \1\ = P5E_CPU1_PE3_TX_C_DP<1> ; \2\ = P5E_CPU1_PE3_TX_DP<1>
PR3918  Q_RES  2K 0.1% CHIP  pkg 0402LF  page 302 : A = HSC_IMON ; B = AGND_HSC

(kicad_pcb
	(version 20260206)
	(generator "pcbnew")
	(generator_version "10.0")
	(general
		(thickness 1.6)
		(legacy_teardrops no)
	)
	(paper "A4")
	(title_block
		(title "03242023_DA0F0TMBIJ0_F0T_Motherboard_J_brd_V01_OCP.brd")
		(comment 1 "Grand Teton / footprints 2533-2535 of 6105")
	)
	(layers
		(0 "F.Cu" signal "TOP")
		(4 "In1.Cu" signal "GND")
		(6 "In2.Cu" signal "IN1")
		(8 "In3.Cu" signal "GND1")
		(10 "In4.Cu" signal "IN2")
		(12 "In5.Cu" signal "GND2")
		(14 "In6.Cu" signal "IN3")
		(16 "In7.Cu" signal "GND3")
		(18 "In8.Cu" signal "VCC")
		(20 "In9.Cu" signal "VCC1")
		(22 "In10.Cu" signal "GND4")
		(24 "In11.Cu" signal "IN4")
		(26 "In12.Cu" signal "GND5")
		(28 "In13.Cu" signal "IN5")
		(30 "In14.Cu" signal "GND6")
		(32 "In15.Cu" signal "IN6")
		(34 "In16.Cu" signal "GND7")
		(2 "B.Cu" signal "BOTTOM")
		(9 "F.Adhes" user "F.Adhesive")
		(11 "B.Adhes" user "B.Adhesive")
		(13 "F.Paste" user "Package Geometry/Pastemask Top")
		(15 "B.Paste" user "Package Geometry/Pastemask Bottom")
		(5 "F.SilkS" user "Ref Des/Silkscreen Top")
		(7 "B.SilkS" user "Ref Des/Silkscreen Bottom")
		(1 "F.Mask" user "Board Geometry/Soldermask Top")
		(3 "B.Mask" user "Board Geometry/Soldermask Bottom")
		(17 "Dwgs.User" user "User.Drawings")
		(19 "Cmts.User" user "User.Comments")
		(21 "Eco1.User" user "User.Eco1")
		(23 "Eco2.User" user "User.Eco2")
		(25 "Edge.Cuts" user "Board Geometry/Outline")
		(27 "Margin" user)
		(31 "F.CrtYd" user "Package Geometry/Place Bound Top")
		(29 "B.CrtYd" user "Package Geometry/Place Bound Bottom")
		(35 "F.Fab" user "Ref Des/Assembly Top")
		(33 "B.Fab" user "Ref Des/Assembly Bottom")
	)
	(footprint ""
		(layer "F.Cu")
		(at 172.047408 -415.900362 180)
		(property "Reference" "Q103"
			(at 1.022096 1.8669 0)
			(unlocked yes)
			(layer "F.SilkS")
			(effects
				(font
					(size 0.7874 0.5842)
					(thickness 0.1524)
				)
				(justify left)
			)
		)
		(property "Value" ""
			(at 0 0 180)
			(layer "F.Fab")
			(effects
				(font
					(size 1.27 1.27)
				)
			)
		)
		(duplicate_pad_numbers_are_jumpers no)
		(fp_line
			(start 1.332738 1.100074)
			(end -1.332738 1.100074)
			(stroke
				(width 0.1524)
				(type default)
			)
			(layer "F.SilkS")
		)
		(fp_line
			(start 1.332738 -1.100074)
			(end 1.332738 1.100074)
			(stroke
				(width 0.1524)
				(type default)
			)
			(layer "F.SilkS")
		)
		(fp_line
			(start 0.4826 -1.100074)
			(end 1.332738 -1.100074)
			(stroke
				(width 0.1524)
				(type default)
			)
			(layer "F.SilkS")
		)
		(fp_line
			(start 0 -0.541274)
			(end 0.4826 -1.100074)
			(stroke
				(width 0.1524)
				(type default)
			)
			(layer "F.SilkS")
		)
		(fp_line
			(start -0.4826 -1.100074)
			(end 0 -0.541274)
			(stroke
				(width 0.1524)
				(type default)
			)
			(layer "F.SilkS")
		)
		(fp_line
			(start -1.332738 1.100074)
			(end -1.332738 -1.100074)
			(stroke
				(width 0.1524)
				(type default)
			)
			(layer "F.SilkS")
		)
		(fp_line
			(start -1.332738 -1.100074)
			(end -0.4826 -1.100074)
			(stroke
				(width 0.1524)
				(type default)
			)
			(layer "F.SilkS")
		)
		(fp_poly
			(pts
				(xy -0.675132 -1.928622) (xy -1.02616 -1.226566) (xy -1.377188 -1.928622)
			)
			(stroke
				(width 0)
				(type default)
			)
			(fill yes)
			(layer "F.SilkS")
		)
		(fp_line
			(start 0.674878 1.100074)
			(end -0.674878 1.100074)
			(stroke
				(width 0.1)
				(type default)
			)
			(layer "F.Fab")
		)
		(fp_line
			(start 0.674878 -1.100074)
			(end 0.674878 1.100074)
			(stroke
				(width 0.1)
				(type default)
			)
			(layer "F.Fab")
		)
		(fp_line
			(start -0.674878 1.100074)
			(end -0.674878 -1.100074)
			(stroke
				(width 0.1)
				(type default)
			)
			(layer "F.Fab")
		)
		(fp_line
			(start -0.674878 -1.100074)
			(end 0.674878 -1.100074)
			(stroke
				(width 0.1)
				(type default)
			)
			(layer "F.Fab")
		)
		(fp_poly
			(pts
				(xy -2.2352 -0.298958) (xy -2.2352 -1.001014) (xy -1.533144 -0.649986)
			)
			(stroke
				(width 0)
				(type default)
			)
			(fill yes)
			(layer "F.Fab")
		)
		(pad "1" smd rect
			(at -0.94996 -0.649986 270)
			(size 0.4318 0.508)
			(layers "F.Cu" "F.Mask" "F.Paste")
			(net "GND")
		)
		(pad "2" smd rect
			(at -0.94996 0 270)
			(size 0.4318 0.508)
			(layers "F.Cu" "F.Mask" "F.Paste")
			(net "GPU_HMC_PRSNT_N")
		)
		(pad "3" smd rect
			(at -0.94996 0.649986 270)
			(size 0.4318 0.508)
			(layers "F.Cu" "F.Mask" "F.Paste")
			(net "GPU_HMC_PRSNT_ISO_N")
		)
		(pad "4" smd rect
			(at 0.94996 0.649986 270)
			(size 0.4318 0.508)
			(layers "F.Cu" "F.Mask" "F.Paste")
			(net "GND")
		)
		(pad "5" smd rect
			(at 0.94996 0 270)
			(size 0.4318 0.508)
			(layers "F.Cu" "F.Mask" "F.Paste")
			(net "GPU_HMC_PRSNT")
		)
		(pad "6" smd rect
			(at 0.94996 -0.649986 270)
			(size 0.4318 0.508)
			(layers "F.Cu" "F.Mask" "F.Paste")
			(net "GPU_HMC_PRSNT")
		)
	)
	(footprint ""
		(layer "F.Cu")
		(at 194.856608 -401.800822 180)
		(property "Reference" "PR3918"
			(at 0 0 180)
			(layer "F.SilkS")
			(hide yes)
			(effects
				(font
					(size 1.27 1.27)
				)
			)
		)
		(property "Value" ""
			(at 0 0 180)
			(layer "F.Fab")
			(effects
				(font
					(size 1.27 1.27)
				)
			)
		)
		(duplicate_pad_numbers_are_jumpers no)
		(fp_line
			(start 0.7874 0.4064)
			(end -0.7874 0.4064)
			(stroke
				(width 0.1524)
				(type default)
			)
			(layer "F.SilkS")
		)
		(fp_line
			(start 0.7874 -0.4064)
			(end 0.7874 0.4064)
			(stroke
				(width 0.1524)
				(type default)
			)
			(layer "F.SilkS")
		)
		(fp_line
			(start -0.7874 0.4064)
			(end -0.7874 -0.4064)
			(stroke
				(width 0.1524)
				(type default)
			)
			(layer "F.SilkS")
		)
		(fp_line
			(start -0.7874 -0.4064)
			(end 0.7874 -0.4064)
			(stroke
				(width 0.1524)
				(type default)
			)
			(layer "F.SilkS")
		)
		(fp_line
			(start 0.67945 0.3048)
			(end 0.120396 0.3048)
			(stroke
				(width 0.1)
				(type default)
			)
			(layer "F.Fab")
		)
		(fp_line
			(start 0.67945 -0.3048)
			(end 0.67945 0.3048)
			(stroke
				(width 0.1)
				(type default)
			)
			(layer "F.Fab")
		)
		(fp_line
			(start 0.12065 -0.2794)
			(end 0.12065 -0.3048)
			(stroke
				(width 0.1)
				(type default)
			)
			(layer "F.Fab")
		)
		(fp_line
			(start 0.12065 -0.3048)
			(end 0.67945 -0.3048)
			(stroke
				(width 0.1)
				(type default)
			)
			(layer "F.Fab")
		)
		(fp_line
			(start 0.120396 0.3048)
			(end 0.120396 0.2794)
			(stroke
				(width 0.1)
				(type default)
			)
			(layer "F.Fab")
		)
		(fp_line
			(start 0.120396 0.2794)
			(end -0.12065 0.2794)
			(stroke
				(width 0.1)
				(type default)
			)
			(layer "F.Fab")
		)
		(fp_line
			(start -0.12065 0.3048)
			(end -0.67945 0.3048)
			(stroke
				(width 0.1)
				(type default)
			)
			(layer "F.Fab")
		)
		(fp_line
			(start -0.12065 0.2794)
			(end -0.12065 0.3048)
			(stroke
				(width 0.1)
				(type default)
			)
			(layer "F.Fab")
		)
		(fp_line
			(start -0.12065 -0.2794)
			(end 0.12065 -0.2794)
			(stroke
				(width 0.1)
				(type default)
			)
			(layer "F.Fab")
		)
		(fp_line
			(start -0.12065 -0.305054)
			(end -0.12065 -0.2794)
			(stroke
				(width 0.1)
				(type default)
			)
			(layer "F.Fab")
		)
		(fp_line
			(start -0.67945 0.3048)
			(end -0.67945 -0.305054)
			(stroke
				(width 0.1)
				(type default)
			)
			(layer "F.Fab")
		)
		(fp_line
			(start -0.67945 -0.305054)
			(end -0.12065 -0.305054)
			(stroke
				(width 0.1)
				(type default)
			)
			(layer "F.Fab")
		)
		(pad "1" smd circle
			(at -0.40005 0 180)
			(size 0 0)
			(layers "F.Cu" "F.Mask" "F.Paste")
			(net "HSC_IMON")
		)
		(pad "2" smd circle
			(at 0.40005 0 180)
			(size 0 0)
			(layers "F.Cu" "F.Mask" "F.Paste")
			(net "AGND_HSC")
		)
	)
	(footprint ""
		(layer "F.Cu")
		(at 165.275514 -408.517344 -90)
		(property "Reference" "C1545"
			(at 0 0 270)
			(layer "F.SilkS")
			(hide yes)
			(effects
				(font
					(size 1.27 1.27)
				)
			)
		)
		(property "Value" ""
			(at 0 0 270)
			(layer "F.Fab")
			(effects
				(font
					(size 1.27 1.27)
				)
			)
		)
		(duplicate_pad_numbers_are_jumpers no)
		(fp_line
			(start -0.299974 0.150114)
			(end -0.299974 -0.150114)
			(stroke
				(width 0.1)
				(type default)
			)
			(layer "F.Fab")
		)
		(fp_line
			(start 0.299974 0.150114)
			(end -0.299974 0.150114)
			(stroke
				(width 0.1)
				(type default)
			)
			(layer "F.Fab")
		)
		(fp_line
			(start -0.299974 -0.150114)
			(end 0.299974 -0.150114)
			(stroke
				(width 0.1)
				(type default)
			)
			(layer "F.Fab")
		)
		(fp_line
			(start 0.299974 -0.150114)
			(end 0.299974 0.150114)
			(stroke
				(width 0.1)
				(type default)
			)
			(layer "F.Fab")
		)
		(pad "1" smd rect
			(at -0.2667 0 270)
			(size 0.3048 0.381)
			(layers "F.Cu" "F.Mask" "F.Paste")
			(net "P5E_CPU1_PE3_TX_C_DP<1>")
		)
		(pad "2" smd rect
			(at 0.2667 0 270)
			(size 0.3048 0.381)
			(layers "F.Cu" "F.Mask" "F.Paste")
			(net "P5E_CPU1_PE3_TX_DP<1>")
		)
	)
)
